# T6G (Grand Teton) — schematic netlist excerpt (pin names and nets, part order shuffled) for the footprints in the layout excerpt that follows; sources: Cadence DE-HDL packaged netlist, KiCad conversion of 04192023_DAF0TMB3IC0_F0TG_MB_C_brd_V02_OCP.brd

R5054  Q_RES  0 5% CHIP  pkg 0402LF  page 187 : A = P3V3_RTC_AUX_R ; B = P1V5_BAT_OUT_R
R9006  Q_RES  10K 1% CHIP  pkg 0402LF  page 123 : A = P3V3_AUX ; B = PRSNT_CABLE_SWB_B2_N

(kicad_pcb
	(version 20260206)
	(generator "pcbnew")
	(generator_version "10.0")
	(general
		(thickness 1.6)
		(legacy_teardrops no)
	)
	(paper "A4")
	(title_block
		(title "04192023_DAF0TMB3IC0_F0TG_MB_C_brd_V02_OCP.brd")
		(comment 1 "Grand Teton / footprints 4851-4852 of 8354")
	)
	(layers
		(0 "F.Cu" signal "TOP")
		(4 "In1.Cu" signal "GND")
		(6 "In2.Cu" signal "IN1")
		(8 "In3.Cu" signal "GND1")
		(10 "In4.Cu" signal "IN2")
		(12 "In5.Cu" signal "GND2")
		(14 "In6.Cu" signal "IN3")
		(16 "In7.Cu" signal "GND3")
		(18 "In8.Cu" signal "VCC")
		(20 "In9.Cu" signal "VCC1")
		(22 "In10.Cu" signal "GND4")
		(24 "In11.Cu" signal "IN4")
		(26 "In12.Cu" signal "GND5")
		(28 "In13.Cu" signal "IN5")
		(30 "In14.Cu" signal "GND6")
		(32 "In15.Cu" signal "IN6")
		(34 "In16.Cu" signal "GND7")
		(2 "B.Cu" signal "BOTTOM")
		(9 "F.Adhes" user "F.Adhesive")
		(11 "B.Adhes" user "B.Adhesive")
		(13 "F.Paste" user "Package Geometry/Pastemask Top")
		(15 "B.Paste" user "Package Geometry/Pastemask Bottom")
		(5 "F.SilkS" user "Ref Des/Silkscreen Top")
		(7 "B.SilkS" user "Ref Des/Silkscreen Bottom")
		(1 "F.Mask" user "Board Geometry/Soldermask Top")
		(3 "B.Mask" user "Board Geometry/Soldermask Bottom")
		(17 "Dwgs.User" user "User.Drawings")
		(19 "Cmts.User" user "User.Comments")
		(21 "Eco1.User" user "User.Eco1")
		(23 "Eco2.User" user "User.Eco2")
		(25 "Edge.Cuts" user "Board Geometry/Outline")
		(27 "Margin" user)
		(31 "F.CrtYd" user "Package Geometry/Place Bound Top")
		(29 "B.CrtYd" user "Package Geometry/Place Bound Bottom")
		(35 "F.Fab" user "Ref Des/Assembly Top")
		(33 "B.Fab" user "Ref Des/Assembly Bottom")
	)
	(footprint ""
		(layer "F.Cu")
		(at 325.314056 -23.826216 -90)
		(property "Reference" "R5054"
			(at 0 0 270)
			(layer "F.SilkS")
			(hide yes)
			(effects
				(font
					(size 1.27 1.27)
				)
			)
		)
		(property "Value" ""
			(at 0 0 270)
			(layer "F.Fab")
			(effects
				(font
					(size 1.27 1.27)
				)
			)
		)
		(duplicate_pad_numbers_are_jumpers no)
		(fp_line
			(start -0.7874 0.4064)
			(end -0.7874 -0.4064)
			(stroke
				(width 0.1524)
				(type default)
			)
			(layer "F.SilkS")
		)
		(fp_line
			(start 0.7874 0.4064)
			(end -0.7874 0.4064)
			(stroke
				(width 0.1524)
				(type default)
			)
			(layer "F.SilkS")
		)
		(fp_line
			(start -0.7874 -0.4064)
			(end 0.7874 -0.4064)
			(stroke
				(width 0.1524)
				(type default)
			)
			(layer "F.SilkS")
		)
		(fp_line
			(start 0.7874 -0.4064)
			(end 0.7874 0.4064)
			(stroke
				(width 0.1524)
				(type default)
			)
			(layer "F.SilkS")
		)
		(fp_line
			(start -0.67945 0.3048)
			(end -0.67945 -0.305054)
			(stroke
				(width 0.1)
				(type default)
			)
			(layer "F.Fab")
		)
		(fp_line
			(start -0.12065 0.3048)
			(end -0.67945 0.3048)
			(stroke
				(width 0.1)
				(type default)
			)
			(layer "F.Fab")
		)
		(fp_line
			(start 0.120396 0.3048)
			(end 0.120396 0.2794)
			(stroke
				(width 0.1)
				(type default)
			)
			(layer "F.Fab")
		)
		(fp_line
			(start 0.67945 0.3048)
			(end 0.120396 0.3048)
			(stroke
				(width 0.1)
				(type default)
			)
			(layer "F.Fab")
		)
		(fp_line
			(start -0.12065 0.2794)
			(end -0.12065 0.3048)
			(stroke
				(width 0.1)
				(type default)
			)
			(layer "F.Fab")
		)
		(fp_line
			(start 0.120396 0.2794)
			(end -0.12065 0.2794)
			(stroke
				(width 0.1)
				(type default)
			)
			(layer "F.Fab")
		)
		(fp_line
			(start -0.12065 -0.2794)
			(end 0.12065 -0.2794)
			(stroke
				(width 0.1)
				(type default)
			)
			(layer "F.Fab")
		)
		(fp_line
			(start 0.12065 -0.2794)
			(end 0.12065 -0.3048)
			(stroke
				(width 0.1)
				(type default)
			)
			(layer "F.Fab")
		)
		(fp_line
			(start 0.12065 -0.3048)
			(end 0.67945 -0.3048)
			(stroke
				(width 0.1)
				(type default)
			)
			(layer "F.Fab")
		)
		(fp_line
			(start 0.67945 -0.3048)
			(end 0.67945 0.3048)
			(stroke
				(width 0.1)
				(type default)
			)
			(layer "F.Fab")
		)
		(fp_line
			(start -0.67945 -0.305054)
			(end -0.12065 -0.305054)
			(stroke
				(width 0.1)
				(type default)
			)
			(layer "F.Fab")
		)
		(fp_line
			(start -0.12065 -0.305054)
			(end -0.12065 -0.2794)
			(stroke
				(width 0.1)
				(type default)
			)
			(layer "F.Fab")
		)
		(pad "1" smd circle
			(at -0.40005 0 270)
			(size 0 0)
			(layers "F.Cu" "F.Mask" "F.Paste")
			(net "P3V3_RTC_AUX_R")
		)
		(pad "2" smd circle
			(at 0.40005 0 270)
			(size 0 0)
			(layers "F.Cu" "F.Mask" "F.Paste")
			(net "P1V5_BAT_OUT_R")
		)
	)
	(footprint ""
		(layer "F.Cu")
		(at 172.540422 -417.551616)
		(property "Reference" "R9006"
			(at 0 0 0)
			(layer "F.SilkS")
			(hide yes)
			(effects
				(font
					(size 1.27 1.27)
				)
			)
		)
		(property "Value" ""
			(at 0 0 0)
			(layer "F.Fab")
			(effects
				(font
					(size 1.27 1.27)
				)
			)
		)
		(duplicate_pad_numbers_are_jumpers no)
		(fp_line
			(start -0.7874 -0.4064)
			(end 0.7874 -0.4064)
			(stroke
				(width 0.1524)
				(type default)
			)
			(layer "F.SilkS")
		)
		(fp_line
			(start -0.7874 0.4064)
			(end -0.7874 -0.4064)
			(stroke
				(width 0.1524)
				(type default)
			)
			(layer "F.SilkS")
		)
		(fp_line
			(start 0.7874 -0.4064)
			(end 0.7874 0.4064)
			(stroke
				(width 0.1524)
				(type default)
			)
			(layer "F.SilkS")
		)
		(fp_line
			(start 0.7874 0.4064)
			(end -0.7874 0.4064)
			(stroke
				(width 0.1524)
				(type default)
			)
			(layer "F.SilkS")
		)
		(fp_line
			(start -0.67945 -0.305054)
			(end -0.12065 -0.305054)
			(stroke
				(width 0.1)
				(type default)
			)
			(layer "F.Fab")
		)
		(fp_line
			(start -0.67945 0.3048)
			(end -0.67945 -0.305054)
			(stroke
				(width 0.1)
				(type default)
			)
			(layer "F.Fab")
		)
		(fp_line
			(start -0.12065 -0.305054)
			(end -0.12065 -0.2794)
			(stroke
				(width 0.1)
				(type default)
			)
			(layer "F.Fab")
		)
		(fp_line
			(start -0.12065 -0.2794)
			(end 0.12065 -0.2794)
			(stroke
				(width 0.1)
				(type default)
			)
			(layer "F.Fab")
		)
		(fp_line
			(start -0.12065 0.2794)
			(end -0.12065 0.3048)
			(stroke
				(width 0.1)
				(type default)
			)
			(layer "F.Fab")
		)
		(fp_line
			(start -0.12065 0.3048)
			(end -0.67945 0.3048)
			(stroke
				(width 0.1)
				(type default)
			)
			(layer "F.Fab")
		)
		(fp_line
			(start 0.120396 0.2794)
			(end -0.12065 0.2794)
			(stroke
				(width 0.1)
				(type default)
			)
			(layer "F.Fab")
		)
		(fp_line
			(start 0.120396 0.3048)
			(end 0.120396 0.2794)
			(stroke
				(width 0.1)
				(type default)
			)
			(layer "F.Fab")
		)
		(fp_line
			(start 0.12065 -0.3048)
			(end 0.67945 -0.3048)
			(stroke
				(width 0.1)
				(type default)
			)
			(layer "F.Fab")
		)
		(fp_line
			(start 0.12065 -0.2794)
			(end 0.12065 -0.3048)
			(stroke
				(width 0.1)
				(type default)
			)
			(layer "F.Fab")
		)
		(fp_line
			(start 0.67945 -0.3048)
			(end 0.67945 0.3048)
			(stroke
				(width 0.1)
				(type default)
			)
			(layer "F.Fab")
		)
		(fp_line
			(start 0.67945 0.3048)
			(end 0.120396 0.3048)
			(stroke
				(width 0.1)
				(type default)
			)
			(layer "F.Fab")
		)
		(pad "1" smd circle
			(at -0.40005 0)
			(size 0 0)
			(layers "F.Cu" "F.Mask" "F.Paste")
			(net "P3V3_AUX")
		)
		(pad "2" smd circle
			(at 0.40005 0)
			(size 0 0)
			(layers "F.Cu" "F.Mask" "F.Paste")
			(net "PRSNT_CABLE_SWB_B2_N")
		)
	)
)
